# BASEBOARD_FAB2 (Tioga Pass) — schematic parts with pin connectivity, parts 2349–2354 of 4751; source: Cadence DE-HDL packaged netlist (pstxprt.dat, pstxnet.dat, pstchip.dat)

J1B1  SCONN288_H44441004  SCONN  pkg PIP  page 83
  1  \12v\(1)  = P12V_NVDIMM_KLM
  2  VSS(93)  GROUND  = GND
  3  DQ(4)  BI  = M_K_DQ<5>
  4  VSS(92)  GROUND  = GND
  5  DQ(0)  BI  = M_K_DQ<1>
  6  VSS(91)  GROUND  = GND
  7  DQS9P  BI  = M_K_DQS_DP<9>
  8  DQS9N  BI  = M_K_DQS_DN<9>
  9  VSS(90)  GROUND  = GND
  10  DQ(6)  BI  = M_K_DQ<7>
  11  VSS(89)  GROUND  = GND
  12  DQ(2)  BI  = M_K_DQ<3>
  13  VSS(88)  GROUND  = GND
  14  DQ(12)  BI  = M_K_DQ<13>
  15  VSS(87)  GROUND  = GND
  16  DQ(8)  BI  = M_K_DQ<9>
  17  VSS(86)  GROUND  = GND
  18  DQS10P  BI  = M_K_DQS_DP<10>
  19  DQS10N  BI  = M_K_DQS_DN<10>
  20  VSS(85)  GROUND  = GND
  21  DQ(14)  BI  = M_K_DQ<15>
  22  VSS(84)  GROUND  = GND
  23  DQ(10)  BI  = M_K_DQ<11>
  24  VSS(83)  GROUND  = GND
  25  DQ(20)  BI  = M_K_DQ<21>
  26  VSS(82)  GROUND  = GND
  27  DQ(16)  BI  = M_K_DQ<17>
  28  VSS(81)  GROUND  = GND
  29  DQS11P  BI  = M_K_DQS_DP<11>
  30  DQS11N  BI  = M_K_DQS_DN<11>
  31  VSS(80)  GROUND  = GND
  32  DQ(22)  BI  = M_K_DQ<23>
  33  VSS(79)  GROUND  = GND
  34  DQ(18)  BI  = M_K_DQ<19>
  35  VSS(78)  GROUND  = GND
  36  DQ(28)  BI  = M_K_DQ<29>
  37  VSS(77)  GROUND  = GND
  38  DQ(24)  BI  = M_K_DQ<25>
  39  VSS(76)  GROUND  = GND
  40  DQS12P  BI  = M_K_DQS_DP<12>
  41  DQS12N  BI  = M_K_DQS_DN<12>
  42  VSS(75)  GROUND  = GND
  43  DQ(30)  BI  = M_K_DQ<31>
  44  VSS(74)  GROUND  = GND
  45  DQ(26)  BI  = M_K_DQ<27>
  46  VSS(73)  GROUND  = GND
  47  CB(4)  BI  = M_K_ECC<5>
  48  VSS(72)  GROUND  = GND
  49  CB(0)  BI  = M_K_ECC<1>
  50  VSS(71)  GROUND  = GND
  51  DQS17P  BI  = M_K_DQS_DP<17>
  52  DQS17N  BI  = M_K_DQS_DN<17>
  53  VSS(70)  GROUND  = GND
  54  CB(6)  BI  = M_K_ECC<7>
  55  VSS(69)  GROUND  = GND
  56  CB(2)  BI  = M_K_ECC<3>
  57  VSS(68)  GROUND  = GND
  58  RESET_N  BI  = M_KLM_RST_N
  59  VDD(25)  POWER  = PVDDQ_KLM
  60  CKE(0)  BI  = M_K_CKE<0>
  61  VDD(24)  POWER  = PVDDQ_KLM
  62  ACT_N  BI  = M_K_ACT_N
  63  BG(0)  BI  = M_K_BG<0>
  64  VDD(23)  POWER  = PVDDQ_KLM
  65  A12  BI  = M_K_MA<12>
  66  A9  BI  = M_K_MA<9>
  67  VDD(22)  POWER  = PVDDQ_KLM
  68  A8  BI  = M_K_MA<8>
  69  A6  BI  = M_K_MA<6>
  70  VDD(21)  POWER  = PVDDQ_KLM
  71  A3  BI  = M_K_MA<3>
  72  A1  BI  = M_K_MA<1>
  73  VDD(20)  POWER  = PVDDQ_KLM
  74  CK0P  BI  = M_K_CLK_DP<0>
  75  CK0N  BI  = M_K_CLK_DN<0>
  76  VDD(19)  POWER  = PVDDQ_KLM
  77  VTT(1)  POWER  = PVTT_KLM
  78  EVENT_N  BI  = FM_DIMM_EVENT_COD_N
  79  A0  BI  = M_K_MA<0>
  80  VDD(18)  POWER  = PVDDQ_KLM
  81  BA(0)  BI  = M_K_BA<0>
  82  A16_RAS_N  BI  = M_K_MA<16>
  83  VDD(17)  POWER  = PVDDQ_KLM
  84  S0_N  BI  = M_K_CS_N<0>
  85  VDD(16)  POWER  = PVDDQ_KLM
  86  A15_CAS_N  BI  = M_K_MA<15>
  87  ODT(0)  BI  = M_K_ODT<0>
  88  VDD(15)  POWER  = PVDDQ_KLM
  89  S1_N  BI  = M_K_CS_N<1>
  90  VDD(14)  POWER  = PVDDQ_KLM
  91  ODT(1)  BI  = M_K_ODT<1>
  92  VDD(13)  POWER  = PVDDQ_KLM
  93  S2_N_C(0)  BI  = M_K_CS_N<2>
  94  VSS(67)  GROUND  = GND
  95  DQ(36)  BI  = M_K_DQ<37>
  96  VSS(66)  GROUND  = GND
  97  DQ(32)  BI  = M_K_DQ<33>
  98  VSS(65)  GROUND  = GND
  99  DQS13P  BI  = M_K_DQS_DP<13>
  100  DQS13N  BI  = M_K_DQS_DN<13>
  101  VSS(64)  GROUND  = GND
  102  DQ(38)  BI  = M_K_DQ<39>
  103  VSS(63)  GROUND  = GND
  104  DQ(34)  BI  = M_K_DQ<35>
  105  VSS(62)  GROUND  = GND
  106  DQ(44)  BI  = M_K_DQ<45>
  107  VSS(61)  GROUND  = GND
  108  DQ(40)  BI  = M_K_DQ<41>
  109  VSS(60)  GROUND  = GND
  110  DQS14P  BI  = M_K_DQS_DP<14>
  111  DQS14N  BI  = M_K_DQS_DN<14>
  112  VSS(59)  GROUND  = GND
  113  DQ(46)  BI  = M_K_DQ<47>
  114  VSS(58)  GROUND  = GND
  115  DQ(42)  BI  = M_K_DQ<43>
  116  VSS(57)  GROUND  = GND
  117  DQ(52)  BI  = M_K_DQ<53>
  118  VSS(56)  GROUND  = GND
  119  DQ(48)  BI  = M_K_DQ<49>
  120  VSS(55)  GROUND  = GND
  121  DQS15P  BI  = M_K_DQS_DP<15>
  122  DQS15N  BI  = M_K_DQS_DN<15>
  123  VSS(54)  GROUND  = GND
  124  DQ(54)  BI  = M_K_DQ<55>
  125  VSS(53)  GROUND  = GND
  126  DQ(50)  BI  = M_K_DQ<51>
  127  VSS(52)  GROUND  = GND
  128  DQ(60)  BI  = M_K_DQ<61>
  129  VSS(51)  GROUND  = GND
  130  DQ(56)  BI  = M_K_DQ<57>
  131  VSS(50)  GROUND  = GND
  132  DQS16P  BI  = M_K_DQS_DP<16>
  133  DQS16N  BI  = M_K_DQS_DN<16>
  134  VSS(49)  GROUND  = GND
  135  DQ(62)  BI  = M_K_DQ<63>
  136  VSS(48)  GROUND  = GND
  137  DQ(58)  BI  = M_K_DQ<59>
  138  VSS(47)  GROUND  = GND
  139  SA(0)  BI  = GND
  140  SA(1)  BI  = GND
  141  SCL  BI  = SMB_DDR_KLM_VPP_SCL
  142  VPP(4)  POWER  = PVPP_KLM
  143  VPP(3)  POWER  = PVPP_KLM
  144  RFU(2)  BI  = TP_CH_K_DIMM_K0_RFU_2
  145  \12v\(0)  = P12V_NVDIMM_KLM
  146  VREFCA  BI  = M_K_VREF
  147  VSS(46)  GROUND  = GND
  148  DQ(5)  BI  = M_K_DQ<4>
  149  VSS(45)  GROUND  = GND
  150  DQ(1)  BI  = M_K_DQ<0>
  151  VSS(44)  GROUND  = GND
  152  DQS0N  BI  = M_K_DQS_DN<0>
  153  DQS0P  BI  = M_K_DQS_DP<0>
  154  VSS(43)  GROUND  = GND
  155  DQ(7)  BI  = M_K_DQ<6>
  156  VSS(42)  GROUND  = GND
  157  DQ(3)  BI  = M_K_DQ<2>
  158  VSS(41)  GROUND  = GND
  159  DQ(13)  BI  = M_K_DQ<12>
  160  VSS(40)  GROUND  = GND
  161  DQ(9)  BI  = M_K_DQ<8>
  162  VSS(39)  GROUND  = GND
  163  DQS1N  BI  = M_K_DQS_DN<1>
  164  DQS1P  BI  = M_K_DQS_DP<1>
  165  VSS(38)  GROUND  = GND
  166  DQ(15)  BI  = M_K_DQ<14>
  167  VSS(37)  GROUND  = GND
  168  DQ(11)  BI  = M_K_DQ<10>
  169  VSS(36)  GROUND  = GND
  170  DQ(21)  BI  = M_K_DQ<20>
  171  VSS(35)  GROUND  = GND
  172  DQ(17)  BI  = M_K_DQ<16>
  173  VSS(34)  GROUND  = GND
  174  DQS2N  BI  = M_K_DQS_DN<2>
  175  DQS2P  BI  = M_K_DQS_DP<2>
  176  VSS(33)  GROUND  = GND
  177  DQ(23)  BI  = M_K_DQ<22>
  178  VSS(32)  GROUND  = GND
  179  DQ(19)  BI  = M_K_DQ<18>
  180  VSS(31)  GROUND  = GND
  181  DQ(29)  BI  = M_K_DQ<28>
  182  VSS(30)  GROUND  = GND
  183  DQ(25)  BI  = M_K_DQ<24>
  184  VSS(29)  GROUND  = GND
  185  DQS3N  BI  = M_K_DQS_DN<3>
  186  DQS3P  BI  = M_K_DQS_DP<3>
  187  VSS(28)  GROUND  = GND
  188  DQ(31)  BI  = M_K_DQ<30>
  189  VSS(27)  GROUND  = GND
  190  DQ(27)  BI  = M_K_DQ<26>
  191  VSS(26)  GROUND  = GND
  192  CB(5)  BI  = M_K_ECC<4>
  193  VSS(25)  GROUND  = GND
  194  CB(1)  BI  = M_K_ECC<0>
  195  VSS(24)  GROUND  = GND
  196  DQS8N  BI  = M_K_DQS_DN<8>
  197  DQS8P  BI  = M_K_DQS_DP<8>
  198  VSS(23)  GROUND  = GND
  199  CB(7)  BI  = M_K_ECC<6>
  200  VSS(22)  GROUND  = GND
  201  CB(3)  BI  = M_K_ECC<2>
  202  VSS(21)  GROUND  = GND
  203  CKE(1)  BI  = M_K_CKE<1>
  204  VDD(12)  POWER  = PVDDQ_KLM
  205  RFU(0)  BI  = TP_CH_K_DIMM_K0_RFU_0
  206  VDD(11)  POWER  = PVDDQ_KLM
  207  BG(1)  BI  = M_K_BG<1>
  208  ALERT_N  BI  = M_K_ALERT_N
  209  VDD(10)  POWER  = PVDDQ_KLM
  210  A11  BI  = M_K_MA<11>
  211  A7  BI  = M_K_MA<7>
  212  VDD(9)  POWER  = PVDDQ_KLM
  213  A5  BI  = M_K_MA<5>
  214  A4  BI  = M_K_MA<4>
  215  VDD(8)  POWER  = PVDDQ_KLM
  216  A2  BI  = M_K_MA<2>
  217  VDD(7)  POWER  = PVDDQ_KLM
  218  CK1P  BI  = M_K_CLK_DP<1>
  219  CK1N  BI  = M_K_CLK_DN<1>
  220  VDD(6)  POWER  = PVDDQ_KLM
  221  VTT(0)  POWER  = PVTT_KLM
  222  PAR  BI  = M_K_PAR
  223  VDD(5)  POWER  = PVDDQ_KLM
  224  BA(1)  BI  = M_K_BA<1>
  225  A10  BI  = M_K_MA<10>
  226  VDD(4)  POWER  = PVDDQ_KLM
  227  RFU(1)  BI  = TP_CH_K_DIMM_K0_RFU_1
  228  A14_WE_N  BI  = M_K_MA<14>
  229  VDD(3)  POWER  = PVDDQ_KLM
  230  SAVE_N_NC  BI  = FM_ADR_COMPLETE_KLM_N
  231  VDD(2)  POWER  = PVDDQ_KLM
  232  A13  BI  = M_K_MA<13>
  233  VDD(1)  POWER  = PVDDQ_KLM
  234  A17  BI  = M_K_MA<17>
  235  C(2)  BI  = M_K_C<2>
  236  VDD(0)  POWER  = PVDDQ_KLM
  237  S3_N_C(1)  BI  = M_K_CS_N<3>
  238  SA(2)  BI  = GND
  239  VSS(20)  GROUND  = GND
  240  DQ(37)  BI  = M_K_DQ<36>
  241  VSS(19)  GROUND  = GND
  242  DQ(33)  BI  = M_K_DQ<32>
  243  VSS(18)  GROUND  = GND
  244  DQS4N  BI  = M_K_DQS_DN<4>
  245  DQS4P  BI  = M_K_DQS_DP<4>
  246  VSS(17)  GROUND  = GND
  247  DQ(39)  BI  = M_K_DQ<38>
  248  VSS(16)  GROUND  = GND
  249  DQ(35)  BI  = M_K_DQ<34>
  250  VSS(15)  GROUND  = GND
  251  DQ(45)  BI  = M_K_DQ<44>
  252  VSS(14)  GROUND  = GND
  253  DQ(41)  BI  = M_K_DQ<40>
  254  VSS(13)  GROUND  = GND
  255  DQS5N  BI  = M_K_DQS_DN<5>
  256  DQS5P  BI  = M_K_DQS_DP<5>
  257  VSS(12)  GROUND  = GND
  258  DQ(47)  BI  = M_K_DQ<46>
  259  VSS(11)  GROUND  = GND
  260  DQ(43)  BI  = M_K_DQ<42>
  261  VSS(10)  GROUND  = GND
  262  DQ(53)  BI  = M_K_DQ<52>
  263  VSS(9)  GROUND  = GND
  264  DQ(49)  BI  = M_K_DQ<48>
  265  VSS(8)  GROUND  = GND
  266  DQS6N  BI  = M_K_DQS_DN<6>
  267  DQS6P  BI  = M_K_DQS_DP<6>
  268  VSS(7)  GROUND  = GND
  269  DQ(55)  BI  = M_K_DQ<54>
  270  VSS(6)  GROUND  = GND
  271  DQ(51)  BI  = M_K_DQ<50>
  272  VSS(5)  GROUND  = GND
  273  DQ(61)  BI  = M_K_DQ<60>
  274  VSS(4)  GROUND  = GND
  275  DQ(57)  BI  = M_K_DQ<56>
  276  VSS(3)  GROUND  = GND
  277  DQS7N  BI  = M_K_DQS_DN<7>
  278  DQS7P  BI  = M_K_DQS_DP<7>
  279  VSS(2)  GROUND  = GND
  280  DQ(63)  BI  = M_K_DQ<62>
  281  VSS(1)  GROUND  = GND
  282  DQ(59)  BI  = M_K_DQ<58>
  283  VSS(0)  GROUND  = GND
  284  VDDSPD  BI  = PVPP_KLM
  285  SDA  BI  = SMB_DDR_KLM_VPP_SDA
  286  VPP(1)  POWER  = PVPP_KLM
  287  VPP(0)  POWER  = PVPP_KLM
  288  VPP(2)  POWER  = PVPP_KLM

J1B2  CONN6_C74770005  0.22UF 16V 10% HDR  pkg PIP  page 251
  1  IO1  UNSPEC  = GND
  2  IO2  UNSPEC  = P12V_PUMP
  3  IO3  UNSPEC  = PUMP_TACH_D
  4  IO4  UNSPEC  = PUMP_PWM_OUT_R
  5  IO5  UNSPEC  = PUMP_TACH1_D
  6  IO6  UNSPEC  = TP_PUMP

J1B4  CLX-CONN3A-1-GP  pkg CONN-G3  page 199
  1  \1\  UNSPEC  = A_HSC_HIGH_EN
  2  \2\  UNSPEC  = A_HSC_OCP_SEL
  3  \3\  UNSPEC  = A_HSC_LOW_EN

J1C1  DM-FCI-CONN76-8R-GP-U-01  pkg CONN-G4  page 182
  A1  PCIE_RX_DP0  UNSPEC  = P3E_CPU1_PE3_MP_RXN<8>
  A2  GND1  POWER  = GND
  A3  PCIE_RX_DP6  UNSPEC  = P3E_CPU1_PE3_MP_RXP<14>
  A4  FAN_TACH3  UNSPEC  = GND
  A5  MNG_TX_DP  UNSPEC  = TP_IOA5
  A6  \pmbus_alert#\  UNSPEC  = GND
  A7  PCIE_TX_DP3  UNSPEC  = P3E_CPU1_PE3_MP_C_TXN<11>
  A8  GND2  POWER  = GND
  B1  PCIE_RX_DN0  UNSPEC  = P3E_CPU1_PE3_MP_RXP<8>
  B2  PCIE_RX_DP3  UNSPEC  = P3E_CPU1_PE3_MP_RXN<11>
  B3  PCIE_RX_DN6  UNSPEC  = P3E_CPU1_PE3_MP_RXN<14>
  B4  FAN_TACH2  UNSPEC  = TP_FM_WAKE_N
  B5  MNG_TX_DN  UNSPEC  = IRQ_BOARD_BMC_ALERT_N
  B6  PMBUS_DATA  UNSPEC  = SMB_PEHPCPU1_STBY_LVC3_SDA
  B7  PCIE_TX_DN3  UNSPEC  = P3E_CPU1_PE3_MP_C_TXP<11>
  B8  PCIE_TX_DP0  UNSPEC  = P3E_CPU1_PE3_MP_C_TXN<8>
  C1  GND3  POWER  = GND
  C2  PCIE_RX_DN3  UNSPEC  = P3E_CPU1_PE3_MP_RXP<11>
  C3  GND4  POWER  = GND
  C4  FAN_TACH1  UNSPEC  = FM_BB_BMC_MP_GPIO
  C5  GND5  POWER  = GND
  C6  PMBUS_CLK  UNSPEC  = SMB_PEHPCPU1_STBY_LVC3_SCL
  C7  GND6  POWER  = GND
  C8  PCIE_TX_DN0  UNSPEC  = P3E_CPU1_PE3_MP_C_TXP<8>
  D1  PCIE_RX_DP1  UNSPEC  = P3E_CPU1_PE3_MP_RXN<9>
  D2  GND7  POWER  = GND
  D3  PCIE_RX_DP7  UNSPEC  = P3E_CPU1_PE3_MP_RXN<15>
  D4  FAN_TACH0  UNSPEC  = GND
  D5  MNG_RX_DP  UNSPEC  = SMB_LAN_STBY_LVC3_SDA
  D6  GND8  POWER  = GND
  D7  PCIE_TX_DP4  UNSPEC  = P3E_CPU1_PE3_MP_C_TXN<12>
  D8  GND9  POWER  = GND
  E1  PCIE_RX_DN1  UNSPEC  = P3E_CPU1_PE3_MP_RXP<9>
  E2  PCIE_RX_DP4  UNSPEC  = P3E_CPU1_PE3_MP_RXN<12>
  E3  PCIE_RX_DN7  UNSPEC  = P3E_CPU1_PE3_MP_RXP<15>
  E4  \mated_in#\  UNSPEC  = TP_IOE4
  E5  MNG_RX_DN  UNSPEC  = SMB_LAN_STBY_LVC3_SCL
  E6  PCIE_TX_DP6  UNSPEC  = P3E_CPU1_PE3_MP_C_TXN<14>
  E7  PCIE_TX_DN4  UNSPEC  = P3E_CPU1_PE3_MP_C_TXP<12>
  E8  PCIE_TX_DP1  UNSPEC  = P3E_CPU1_PE3_MP_C_TXN<9>
  F1  GND10  POWER  = GND
  F2  PCIE_RX_DN4  UNSPEC  = P3E_CPU1_PE3_MP_RXP<12>
  F3  GND11  POWER  = GND
  F4  FAN_PWM0  UNSPEC  = TP_IOF4
  F5  MB_SLOT_ID0  UNSPEC  = GND
  F6  PCIE_TX_DN6  UNSPEC  = P3E_CPU1_PE3_MP_C_TXP<14>
  F7  GND12  POWER  = GND
  F8  PCIE_TX_DN1  UNSPEC  = P3E_CPU1_PE3_MP_C_TXP<9>
  G1  PCIE_RX_DP2  UNSPEC  = P3E_CPU1_PE3_MP_RXP<10>
  G2  GND13  POWER  = GND
  G3  COM_TX  UNSPEC  = TP_IOG3
  G4  GND14  POWER  = GND
  G5  MB_SLOT_ID1  UNSPEC  = FM_XRC_PRESENT_N
  G6  GND15  POWER  = GND
  G7  PCIE_TX_DP5  UNSPEC  = P3E_CPU1_PE3_MP_C_TXN<13>
  G8  GND16  POWER  = GND
  H1  PCIE_RX_DN2  UNSPEC  = P3E_CPU1_PE3_MP_RXN<10>
  H2  PCIE_RX_DP5  UNSPEC  = P3E_CPU1_PE3_MP_RXP<13>
  H3  COM_RX  UNSPEC  = TP_IOH3
  H4  PCIE_CLK_100M_DP  UNSPEC  = TP_IOH4
  H5  MB_SLOT_ID2  UNSPEC  = FM_XRC_READY_N
  H6  PCIE_TX_DP7  UNSPEC  = P3E_CPU1_PE3_MP_C_TXN<15>
  H7  PCIE_TX_DN5  UNSPEC  = P3E_CPU1_PE3_MP_C_TXP<13>
  H8  PCIE_TX_DP2  UNSPEC  = P3E_CPU1_PE3_MP_C_TXP<10>
  I1  GND17  POWER  = GND
  I2  PCIE_RX_DN5  UNSPEC  = P3E_CPU1_PE3_MP_RXN<13>
  I3  \mb_on#\  UNSPEC  = GND
  I4  PCIE_CLK_100M_DN  UNSPEC  = TP_IOI4
  I5  \pcie_perst#\  UNSPEC  = GND
  I6  PCIE_TX_DN7  UNSPEC  = P3E_CPU1_PE3_MP_C_TXP<15>
  I7  GND18  POWER  = GND
  I8  PCIE_TX_DN2  UNSPEC  = P3E_CPU1_PE3_MP_C_TXN<10>
  J2  J2  UNSPEC  = GND
  J4  J4  UNSPEC  = GND
  J6  J6  UNSPEC  = GND
  J8  J8  UNSPEC  = GND

J1D1  FCI-CONN12-2R-GP  pkg CONN-G5  page 195
  1_1  \1_1\  UNSPEC  = P12V_PSU
  1_2  \1_2\  UNSPEC  = P12V_PSU
  1_3  \1_3\  UNSPEC  = P12V_PSU
  2_1  \2_1\  UNSPEC  = P12V_PSU
  2_2  \2_2\  UNSPEC  = P12V_PSU
  2_3  \2_3\  UNSPEC  = P12V_PSU
  3_1  \3_1\  UNSPEC  = GND
  3_2  \3_2\  UNSPEC  = GND
  3_3  \3_3\  UNSPEC  = GND
  4_1  \4_1\  UNSPEC  = GND
  4_2  \4_2\  UNSPEC  = GND
  4_3  \4_3\  UNSPEC  = GND
  NP1  NP1  UNSPEC  = NC

J1E1  FCI-CONN12-2R-GP  pkg CONN-G5  page 195
  1_1  \1_1\  UNSPEC  = P12V_PSU
  1_2  \1_2\  UNSPEC  = P12V_PSU
  1_3  \1_3\  UNSPEC  = P12V_PSU
  2_1  \2_1\  UNSPEC  = P12V_PSU
  2_2  \2_2\  UNSPEC  = P12V_PSU
  2_3  \2_3\  UNSPEC  = P12V_PSU
  3_1  \3_1\  UNSPEC  = GND
  3_2  \3_2\  UNSPEC  = GND
  3_3  \3_3\  UNSPEC  = GND
  4_1  \4_1\  UNSPEC  = GND
  4_2  \4_2\  UNSPEC  = GND
  4_3  \4_3\  UNSPEC  = GND
  NP1  NP1  UNSPEC  = NC
